(kicad_pcb
	(version 20260206)
	(generator "pcbnew")
	(generator_version "10.0")
	(general
		(thickness 1.6)
		(legacy_teardrops no)
	)
	(paper "A4")
	(title_block
		(title "fcb — Lightning_FCB_BRD.brd")
		(comment 1 "Lightning (Wiwynn / Facebook NVMe JBOF) / footprints 167-173 of 495")
	)
	(layers
		(0 "F.Cu" signal "TOP")
		(4 "In1.Cu" signal "L2GND")
		(6 "In2.Cu" signal "L3VCC")
		(2 "B.Cu" signal "BOTTOM")
		(9 "F.Adhes" user "F.Adhesive")
		(11 "B.Adhes" user "B.Adhesive")
		(13 "F.Paste" user "Package Geometry/Pastemask Top")
		(15 "B.Paste" user "Package Geometry/Pastemask Bottom")
		(5 "F.SilkS" user "Ref Des/Silkscreen Top")
		(7 "B.SilkS" user "Ref Des/Silkscreen Bottom")
		(1 "F.Mask" user "Board Geometry/Soldermask Top")
		(3 "B.Mask" user "Board Geometry/Soldermask Bottom")
		(17 "Dwgs.User" user "User.Drawings")
		(19 "Cmts.User" user "User.Comments")
		(21 "Eco1.User" user "User.Eco1")
		(23 "Eco2.User" user "User.Eco2")
		(25 "Edge.Cuts" user "Board Geometry/Outline")
		(27 "Margin" user)
		(31 "F.CrtYd" user "Package Geometry/Place Bound Top")
		(29 "B.CrtYd" user "Package Geometry/Place Bound Bottom")
		(35 "F.Fab" user "Ref Des/Assembly Top")
		(33 "B.Fab" user "Ref Des/Assembly Bottom")
	)
	(footprint ""
		(layer "F.Cu")
		(at 23.622 -368.554 90)
		(property "Reference" "PR35"
			(at 0 0 90)
			(layer "F.SilkS")
			(hide yes)
			(effects
				(font
					(size 1.27 1.27)
				)
			)
		)
		(property "Value" "4K7R2J-2-GP"
			(at 0.064008 -3.993896 90)
			(unlocked yes)
			(layer "F.Fab")
			(hide yes)
			(effects
				(font
					(size 1.016 1.016)
					(thickness 0.1524)
				)
			)
		)
		(property "Device Type" "R402H16"
			(at 0.064008 -5.517896 90)
			(unlocked yes)
			(layer "F.Fab")
			(hide yes)
			(effects
				(font
					(size 1.016 1.016)
					(thickness 0.1524)
				)
			)
		)
		(duplicate_pad_numbers_are_jumpers no)
		(fp_line
			(start 0.508 -0.9398)
			(end -0.508 -0.9398)
			(stroke
				(width 0.1524)
				(type default)
			)
			(layer "F.SilkS")
		)
		(fp_line
			(start -0.508 -0.9398)
			(end -0.508 0.9398)
			(stroke
				(width 0.1524)
				(type default)
			)
			(layer "F.SilkS")
		)
		(fp_rect
			(start -0.508 0.9398)
			(end 0.508 -0.9398)
			(stroke
				(width 0)
				(type default)
			)
			(fill no)
			(layer "F.CrtYd")
		)
		(fp_rect
			(start -0.508 0.9398)
			(end 0.508 -0.9398)
			(stroke
				(width 0)
				(type default)
			)
			(fill no)
			(layer "F.Fab")
		)
		(pad "1" smd custom
			(at 0 -0.4445 90)
			(size 0.1397 0.1397)
			(layers "F.Cu" "F.Mask" "F.Paste")
			(net "ADM1276_UV")
			(options
				(clearance outline)
				(anchor circle)
			)
			(primitives
				(gr_poly
					(pts
						(arc
							(start -0.1778 -0.2794)
							(mid -0.249642 -0.249642)
							(end -0.2794 -0.1778)
						)
						(arc
							(start -0.2794 0.1778)
							(mid -0.249642 0.249642)
							(end -0.1778 0.2794)
						)
						(arc
							(start 0.1778 0.2794)
							(mid 0.249642 0.249642)
							(end 0.2794 0.1778)
						)
						(arc
							(start 0.2794 -0.1778)
							(mid 0.249642 -0.249642)
							(end 0.1778 -0.2794)
						)
					)
					(width 0)
					(fill yes)
				)
			)
		)
		(pad "2" smd custom
			(at 0 0.4445 90)
			(size 0.1397 0.1397)
			(layers "F.Cu" "F.Mask" "F.Paste")
			(net "ADM1276_VCAP")
			(options
				(clearance outline)
				(anchor circle)
			)
			(primitives
				(gr_poly
					(pts
						(arc
							(start -0.1778 -0.2794)
							(mid -0.249642 -0.249642)
							(end -0.2794 -0.1778)
						)
						(arc
							(start -0.2794 0.1778)
							(mid -0.249642 0.249642)
							(end -0.1778 0.2794)
						)
						(arc
							(start 0.1778 0.2794)
							(mid 0.249642 0.249642)
							(end 0.2794 0.1778)
						)
						(arc
							(start 0.2794 -0.1778)
							(mid 0.249642 -0.249642)
							(end 0.1778 -0.2794)
						)
					)
					(width 0)
					(fill yes)
				)
			)
		)
	)
	(footprint ""
		(layer "F.Cu")
		(at 18.7452 -250.5964 -90)
		(property "Reference" "PR53"
			(at 0 0 270)
			(layer "F.SilkS")
			(hide yes)
			(effects
				(font
					(size 1.27 1.27)
				)
			)
		)
		(property "Value" "10KR3J-L1-GP"
			(at -0.0254 -2.5146 270)
			(unlocked yes)
			(layer "F.Fab")
			(hide yes)
			(effects
				(font
					(size 1.016 1.016)
					(thickness 0.1524)
				)
			)
		)
		(property "Device Type" "R603H22"
			(at -0.0254 -4.0386 270)
			(unlocked yes)
			(layer "F.Fab")
			(hide yes)
			(effects
				(font
					(size 1.016 1.016)
					(thickness 0.1524)
				)
			)
		)
		(duplicate_pad_numbers_are_jumpers no)
		(fp_line
			(start -0.4826 0)
			(end -0.2032 0)
			(stroke
				(width 0.2032)
				(type default)
			)
			(layer "F.SilkS")
		)
		(fp_line
			(start 0.2032 0)
			(end 0.4826 0)
			(stroke
				(width 0.2032)
				(type default)
			)
			(layer "F.SilkS")
		)
		(fp_rect
			(start -0.5842 1.3335)
			(end 0.5842 -1.3335)
			(stroke
				(width 0)
				(type default)
			)
			(fill no)
			(layer "F.CrtYd")
		)
		(fp_rect
			(start -0.5842 1.3335)
			(end 0.5842 -1.3335)
			(stroke
				(width 0)
				(type default)
			)
			(fill no)
			(layer "F.Fab")
		)
		(pad "1" smd custom
			(at 0 -0.762 270)
			(size 0.2159 0.2159)
			(layers "F.Cu" "F.Mask" "F.Paste")
			(net "P3V3_EN")
			(options
				(clearance outline)
				(anchor circle)
			)
			(primitives
				(gr_poly
					(pts
						(arc
							(start -0.3302 -0.4318)
							(mid -0.402042 -0.402042)
							(end -0.4318 -0.3302)
						)
						(arc
							(start -0.4318 0.3302)
							(mid -0.402042 0.402042)
							(end -0.3302 0.4318)
						)
						(arc
							(start 0.3302 0.4318)
							(mid 0.402042 0.402042)
							(end 0.4318 0.3302)
						)
						(arc
							(start 0.4318 -0.3302)
							(mid 0.402042 -0.402042)
							(end 0.3302 -0.4318)
						)
					)
					(width 0)
					(fill yes)
				)
			)
		)
		(pad "2" smd custom
			(at 0 0.762 270)
			(size 0.2159 0.2159)
			(layers "F.Cu" "F.Mask" "F.Paste")
			(net "GND")
			(options
				(clearance outline)
				(anchor circle)
			)
			(primitives
				(gr_poly
					(pts
						(arc
							(start -0.3302 -0.4318)
							(mid -0.402042 -0.402042)
							(end -0.4318 -0.3302)
						)
						(arc
							(start -0.4318 0.3302)
							(mid -0.402042 0.402042)
							(end -0.3302 0.4318)
						)
						(arc
							(start 0.3302 0.4318)
							(mid 0.402042 0.402042)
							(end 0.4318 0.3302)
						)
						(arc
							(start 0.4318 -0.3302)
							(mid 0.402042 -0.402042)
							(end 0.3302 -0.4318)
						)
					)
					(width 0)
					(fill yes)
				)
			)
		)
	)
	(footprint ""
		(layer "F.Cu")
		(at 16.002 -67.564)
		(property "Reference" "R60"
			(at 0 0 0)
			(layer "F.SilkS")
			(hide yes)
			(effects
				(font
					(size 1.27 1.27)
				)
			)
		)
		(property "Value" "4K7R2F-GP"
			(at 0.064008 -3.993896 0)
			(unlocked yes)
			(layer "F.Fab")
			(hide yes)
			(effects
				(font
					(size 1.016 1.016)
					(thickness 0.1524)
				)
			)
		)
		(property "Device Type" "R402H16"
			(at 0.064008 -5.517896 0)
			(unlocked yes)
			(layer "F.Fab")
			(hide yes)
			(effects
				(font
					(size 1.016 1.016)
					(thickness 0.1524)
				)
			)
		)
		(duplicate_pad_numbers_are_jumpers no)
		(fp_line
			(start -0.508 -0.9398)
			(end -0.508 0.9398)
			(stroke
				(width 0.1524)
				(type default)
			)
			(layer "F.SilkS")
		)
		(fp_line
			(start 0.508 -0.9398)
			(end -0.508 -0.9398)
			(stroke
				(width 0.1524)
				(type default)
			)
			(layer "F.SilkS")
		)
		(fp_rect
			(start -0.508 0.9398)
			(end 0.508 -0.9398)
			(stroke
				(width 0)
				(type default)
			)
			(fill no)
			(layer "F.CrtYd")
		)
		(fp_rect
			(start -0.508 0.9398)
			(end 0.508 -0.9398)
			(stroke
				(width 0)
				(type default)
			)
			(fill no)
			(layer "F.Fab")
		)
		(pad "1" smd custom
			(at 0 -0.4445)
			(size 0.1397 0.1397)
			(layers "F.Cu" "F.Mask" "F.Paste")
			(net "P3V3")
			(options
				(clearance outline)
				(anchor circle)
			)
			(primitives
				(gr_poly
					(pts
						(arc
							(start -0.1778 -0.2794)
							(mid -0.249642 -0.249642)
							(end -0.2794 -0.1778)
						)
						(arc
							(start -0.2794 0.1778)
							(mid -0.249642 0.249642)
							(end -0.1778 0.2794)
						)
						(arc
							(start 0.1778 0.2794)
							(mid 0.249642 0.249642)
							(end 0.2794 0.1778)
						)
						(arc
							(start 0.2794 -0.1778)
							(mid 0.249642 -0.249642)
							(end 0.1778 -0.2794)
						)
					)
					(width 0)
					(fill yes)
				)
			)
		)
		(pad "2" smd custom
			(at 0 0.4445)
			(size 0.1397 0.1397)
			(layers "F.Cu" "F.Mask" "F.Paste")
			(net "I2C_C_SDA_CONN_R")
			(options
				(clearance outline)
				(anchor circle)
			)
			(primitives
				(gr_poly
					(pts
						(arc
							(start -0.1778 -0.2794)
							(mid -0.249642 -0.249642)
							(end -0.2794 -0.1778)
						)
						(arc
							(start -0.2794 0.1778)
							(mid -0.249642 0.249642)
							(end -0.1778 0.2794)
						)
						(arc
							(start 0.1778 0.2794)
							(mid 0.249642 0.249642)
							(end 0.2794 0.1778)
						)
						(arc
							(start 0.2794 -0.1778)
							(mid 0.249642 -0.249642)
							(end 0.1778 -0.2794)
						)
					)
					(width 0)
					(fill yes)
				)
			)
		)
	)
	(footprint ""
		(layer "F.Cu")
		(at 43.8404 -394.1064 90)
		(property "Reference" "TC10"
			(at 0 0 90)
			(layer "F.SilkS")
			(hide yes)
			(effects
				(font
					(size 1.27 1.27)
				)
			)
		)
		(property "Value" "ST68U16VDM-1-GP"
			(at 0 -9.6012 90)
			(unlocked yes)
			(layer "F.Fab")
			(hide yes)
			(effects
				(font
					(size 1.016 1.016)
					(thickness 0.1524)
				)
			)
		)
		(property "Device Type" "CT7343H79"
			(at 0 -11.1252 90)
			(unlocked yes)
			(layer "F.Fab")
			(hide yes)
			(effects
				(font
					(size 1.016 1.016)
					(thickness 0.1524)
				)
			)
		)
		(duplicate_pad_numbers_are_jumpers no)
		(fp_line
			(start 2.286 -4.8768)
			(end -2.286 -4.8768)
			(stroke
				(width 0.1524)
				(type default)
			)
			(layer "F.SilkS")
		)
		(fp_line
			(start -2.286 -4.8768)
			(end -2.286 -2.032)
			(stroke
				(width 0.1524)
				(type default)
			)
			(layer "F.SilkS")
		)
		(fp_line
			(start 2.1082 -4.699)
			(end -2.1082 -4.699)
			(stroke
				(width 0.508)
				(type default)
			)
			(layer "F.SilkS")
		)
		(fp_line
			(start 2.286 -2.032)
			(end 2.286 -4.8768)
			(stroke
				(width 0.1524)
				(type default)
			)
			(layer "F.SilkS")
		)
		(fp_line
			(start 2.286 2.032)
			(end 2.286 4.8768)
			(stroke
				(width 0.1524)
				(type default)
			)
			(layer "F.SilkS")
		)
		(fp_line
			(start 2.286 4.8768)
			(end -2.286 4.8768)
			(stroke
				(width 0.1524)
				(type default)
			)
			(layer "F.SilkS")
		)
		(fp_line
			(start -2.286 4.8768)
			(end -2.286 2.032)
			(stroke
				(width 0.1524)
				(type default)
			)
			(layer "F.SilkS")
		)
		(fp_rect
			(start -2.1463 3.6449)
			(end 2.1463 -3.6449)
			(stroke
				(width 0)
				(type default)
			)
			(fill no)
			(layer "F.CrtYd")
		)
		(fp_poly
			(pts
				(xy -2.54 4.953) (xy -2.54 4.2926) (xy -3.81 4.2926) (xy -3.81 -4.2926) (xy -2.54 -4.2926) (xy -2.54 -4.953)
				(xy 2.54 -4.953) (xy 2.54 -4.2926) (xy 3.81 -4.2926) (xy 3.81 -1.6256) (xy 2.1463 -1.6256) (xy 2.1463 -3.6449)
				(xy -2.1463 -3.6449) (xy -2.1463 3.6449) (xy 2.1463 3.6449) (xy 2.1463 -1.6129) (xy 3.81 -1.6129)
				(xy 3.81 4.2926) (xy 2.54 4.2926) (xy 2.54 4.953)
			)
			(stroke
				(width 0)
				(type default)
			)
			(fill no)
			(layer "F.CrtYd")
		)
		(fp_rect
			(start 2.54 4.2926)
			(end 3.81 -4.2926)
			(stroke
				(width 0)
				(type default)
			)
			(fill no)
			(layer "F.Fab")
		)
		(fp_rect
			(start -3.81 4.2926)
			(end -2.54 -4.2926)
			(stroke
				(width 0)
				(type default)
			)
			(fill no)
			(layer "F.Fab")
		)
		(fp_rect
			(start -2.54 4.953)
			(end 2.54 -4.953)
			(stroke
				(width 0)
				(type default)
			)
			(fill no)
			(layer "F.Fab")
		)
		(pad "1" smd rect
			(at 0 -3.1496 90)
			(size 2.413 2.286)
			(layers "F.Cu" "F.Mask" "F.Paste")
			(net "P12V")
		)
		(pad "2" smd rect
			(at 0 3.1496 90)
			(size 2.413 2.286)
			(layers "F.Cu" "F.Mask" "F.Paste")
			(net "GND")
		)
		(zone
			(layer "F.Cu")
			(hatch none 0.5)
			(connect_pads
				(clearance 0)
			)
			(min_thickness 0.25)
			(keepout
				(tracks allowed)
				(vias not_allowed)
				(pads allowed)
				(copperpour not_allowed)
				(footprints allowed)
			)
			(placement
				(enabled no)
				(sheetname "")
			)
			(fill
				(thermal_gap 0.5)
				(thermal_bridge_width 0.5)
				(island_removal_mode 0)
			)
			(polygon
				(pts
					(xy 42.1513 -395.6177) (xy 39.243 -395.6177) (xy 39.243 -392.5951) (xy 42.1386 -392.5951) (xy 42.4688 -392.5951)
					(xy 42.4688 -395.6177)
				)
			)
		)
		(zone
			(layer "F.Cu")
			(hatch none 0.5)
			(connect_pads
				(clearance 0)
			)
			(min_thickness 0.25)
			(keepout
				(tracks allowed)
				(vias not_allowed)
				(pads allowed)
				(copperpour not_allowed)
				(footprints allowed)
			)
			(placement
				(enabled no)
				(sheetname "")
			)
			(fill
				(thermal_gap 0.5)
				(thermal_bridge_width 0.5)
				(island_removal_mode 0)
			)
			(polygon
				(pts
					(xy 48.4378 -392.5951) (xy 48.4378 -395.6177) (xy 45.5422 -395.6177) (xy 45.212 -395.6177) (xy 45.212 -392.5951)
					(xy 45.5422 -392.5951)
				)
			)
		)
	)
	(footprint ""
		(layer "F.Cu")
		(at 18.644362 -157.505908 90)
		(property "Reference" "F2"
			(at 0 0 90)
			(layer "F.SilkS")
			(hide yes)
			(effects
				(font
					(size 1.27 1.27)
				)
			)
		)
		(property "Value" "FUSE-3A15V-GP"
			(at 0.2286 -10.5918 90)
			(unlocked yes)
			(layer "F.Fab")
			(hide yes)
			(effects
				(font
					(size 1.016 1.016)
					(thickness 0.1524)
				)
			)
		)
		(property "Device Type" "FUSE-7452-UH50"
			(at 0.2286 -12.4968 90)
			(unlocked yes)
			(layer "F.Fab")
			(hide yes)
			(effects
				(font
					(size 1.016 1.016)
					(thickness 0.1524)
				)
			)
		)
		(duplicate_pad_numbers_are_jumpers no)
		(fp_line
			(start 4.9276 -2.921)
			(end 4.9276 2.921)
			(stroke
				(width 0.1524)
				(type default)
			)
			(layer "F.SilkS")
		)
		(fp_line
			(start -4.9276 -2.921)
			(end 4.9276 -2.921)
			(stroke
				(width 0.1524)
				(type default)
			)
			(layer "F.SilkS")
		)
		(fp_line
			(start 4.9276 2.921)
			(end -4.9276 2.921)
			(stroke
				(width 0.1524)
				(type default)
			)
			(layer "F.SilkS")
		)
		(fp_line
			(start -4.9276 2.921)
			(end -4.9276 -2.921)
			(stroke
				(width 0.1524)
				(type default)
			)
			(layer "F.SilkS")
		)
		(fp_poly
			(pts
				(xy -5.08 3.0988) (xy 5.08 3.0988) (xy 5.08 -3.0988) (xy -5.08 -3.0988)
			)
			(stroke
				(width 0)
				(type default)
			)
			(fill no)
			(layer "F.CrtYd")
		)
		(fp_poly
			(pts
				(xy -5.08 -3.0988) (xy 5.08 -3.0988) (xy 5.08 3.0988) (xy -5.08 3.0988)
			)
			(stroke
				(width 0)
				(type default)
			)
			(fill no)
			(layer "F.Fab")
		)
		(pad "1" smd rect
			(at -3.4036 0 90)
			(size 2.2098 5.2832)
			(layers "F.Cu" "F.Mask" "F.Paste")
			(net "P12V_FAN5")
		)
		(pad "2" smd rect
			(at 3.4036 0 90)
			(size 2.2098 5.2832)
			(layers "F.Cu" "F.Mask" "F.Paste")
			(net "P12V")
		)
	)
	(footprint ""
		(layer "F.Cu")
		(at 36.068 -378.333 180)
		(property "Reference" "PR26"
			(at 0 0 180)
			(layer "F.SilkS")
			(hide yes)
			(effects
				(font
					(size 1.27 1.27)
				)
			)
		)
		(property "Value" "10R2F-L-GP"
			(at 0.064008 -3.993896 180)
			(unlocked yes)
			(layer "F.Fab")
			(hide yes)
			(effects
				(font
					(size 1.016 1.016)
					(thickness 0.1524)
				)
			)
		)
		(property "Device Type" "R402H14"
			(at 0.064008 -5.517896 180)
			(unlocked yes)
			(layer "F.Fab")
			(hide yes)
			(effects
				(font
					(size 1.016 1.016)
					(thickness 0.1524)
				)
			)
		)
		(duplicate_pad_numbers_are_jumpers no)
		(fp_line
			(start 0.508 -0.9398)
			(end -0.508 -0.9398)
			(stroke
				(width 0.1524)
				(type default)
			)
			(layer "F.SilkS")
		)
		(fp_line
			(start -0.508 -0.9398)
			(end -0.508 0.9398)
			(stroke
				(width 0.1524)
				(type default)
			)
			(layer "F.SilkS")
		)
		(fp_rect
			(start -0.508 0.9398)
			(end 0.508 -0.9398)
			(stroke
				(width 0)
				(type default)
			)
			(fill no)
			(layer "F.CrtYd")
		)
		(fp_rect
			(start -0.508 0.9398)
			(end 0.508 -0.9398)
			(stroke
				(width 0)
				(type default)
			)
			(fill no)
			(layer "F.Fab")
		)
		(pad "1" smd custom
			(at 0 -0.4445 180)
			(size 0.1397 0.1397)
			(layers "F.Cu" "F.Mask" "F.Paste")
			(net "ADM1276_GATE")
			(options
				(clearance outline)
				(anchor circle)
			)
			(primitives
				(gr_poly
					(pts
						(arc
							(start -0.1778 -0.2794)
							(mid -0.249642 -0.249642)
							(end -0.2794 -0.1778)
						)
						(arc
							(start -0.2794 0.1778)
							(mid -0.249642 0.249642)
							(end -0.1778 0.2794)
						)
						(arc
							(start 0.1778 0.2794)
							(mid 0.249642 0.249642)
							(end 0.2794 0.1778)
						)
						(arc
							(start 0.2794 -0.1778)
							(mid 0.249642 -0.249642)
							(end 0.1778 -0.2794)
						)
					)
					(width 0)
					(fill yes)
				)
			)
		)
		(pad "2" smd custom
			(at 0 0.4445 180)
			(size 0.1397 0.1397)
			(layers "F.Cu" "F.Mask" "F.Paste")
			(net "ADM1276_GATE_DRV1")
			(options
				(clearance outline)
				(anchor circle)
			)
			(primitives
				(gr_poly
					(pts
						(arc
							(start -0.1778 -0.2794)
							(mid -0.249642 -0.249642)
							(end -0.2794 -0.1778)
						)
						(arc
							(start -0.2794 0.1778)
							(mid -0.249642 0.249642)
							(end -0.1778 0.2794)
						)
						(arc
							(start 0.1778 0.2794)
							(mid 0.249642 0.249642)
							(end 0.2794 0.1778)
						)
						(arc
							(start 0.2794 -0.1778)
							(mid 0.249642 -0.249642)
							(end 0.1778 -0.2794)
						)
					)
					(width 0)
					(fill yes)
				)
			)
		)
	)
	(footprint ""
		(layer "F.Cu")
		(at 17.0688 -179.8828 180)
		(property "Reference" "C54"
			(at 0 0 180)
			(layer "F.SilkS")
			(hide yes)
			(effects
				(font
					(size 1.27 1.27)
				)
			)
		)
		(property "Value" "SCD1U50V3KX-GP"
			(at 0 -2.8194 180)
			(unlocked yes)
			(layer "F.Fab")
			(hide yes)
			(effects
				(font
					(size 1.016 1.016)
					(thickness 0.1524)
				)
			)
		)
		(property "Device Type" "C603H36"
			(at 0 -4.3434 180)
			(unlocked yes)
			(layer "F.Fab")
			(hide yes)
			(effects
				(font
					(size 1.016 1.016)
					(thickness 0.1524)
				)
			)
		)
		(duplicate_pad_numbers_are_jumpers no)
		(fp_line
			(start 0.508 0)
			(end -0.508 0)
			(stroke
				(width 0.2032)
				(type default)
			)
			(layer "F.SilkS")
		)
		(fp_rect
			(start -0.5842 1.3335)
			(end 0.5842 -1.3335)
			(stroke
				(width 0)
				(type default)
			)
			(fill no)
			(layer "F.CrtYd")
		)
		(fp_rect
			(start -0.5842 1.3335)
			(end 0.5842 -1.3335)
			(stroke
				(width 0)
				(type default)
			)
			(fill no)
			(layer "F.Fab")
		)
		(pad "1" smd custom
			(at 0 -0.762 180)
			(size 0.2159 0.2159)
			(layers "F.Cu" "F.Mask" "F.Paste")
			(net "P3V3")
			(options
				(clearance outline)
				(anchor circle)
			)
			(primitives
				(gr_poly
					(pts
						(arc
							(start -0.3302 -0.4318)
							(mid -0.402042 -0.402042)
							(end -0.4318 -0.3302)
						)
						(arc
							(start -0.4318 0.3302)
							(mid -0.402042 0.402042)
							(end -0.3302 0.4318)
						)
						(arc
							(start 0.3302 0.4318)
							(mid 0.402042 0.402042)
							(end 0.4318 0.3302)
						)
						(arc
							(start 0.4318 -0.3302)
							(mid 0.402042 -0.402042)
							(end 0.3302 -0.4318)
						)
					)
					(width 0)
					(fill yes)
				)
			)
		)
		(pad "2" smd custom
			(at 0 0.762 180)
			(size 0.2159 0.2159)
			(layers "F.Cu" "F.Mask" "F.Paste")
			(net "GND")
			(options
				(clearance outline)
				(anchor circle)
			)
			(primitives
				(gr_poly
					(pts
						(arc
							(start -0.3302 -0.4318)
							(mid -0.402042 -0.402042)
							(end -0.4318 -0.3302)
						)
						(arc
							(start -0.4318 0.3302)
							(mid -0.402042 0.402042)
							(end -0.3302 0.4318)
						)
						(arc
							(start 0.3302 0.4318)
							(mid 0.402042 0.402042)
							(end 0.4318 0.3302)
						)
						(arc
							(start 0.4318 -0.3302)
							(mid 0.402042 -0.402042)
							(end 0.3302 -0.4318)
						)
					)
					(width 0)
					(fill yes)
				)
			)
		)
	)
)
